(kicad_pcb
	(version 20260206)
	(generator "pcbnew")
	(generator_version "10.0")
	(general
		(thickness 1.6)
		(legacy_teardrops no)
	)
	(paper "A4")
	(title_block
		(title "Wiwynn_Tioga_Pass_MB.brd")
		(comment 1 "Tioga Pass / footprints 2410-2416 of 4770")
	)
	(layers
		(0 "F.Cu" signal "TOP")
		(4 "In1.Cu" signal "L2GND")
		(6 "In2.Cu" signal "L3")
		(8 "In3.Cu" signal "L4GND")
		(10 "In4.Cu" signal "L5")
		(12 "In5.Cu" signal "L6GND")
		(14 "In6.Cu" signal "L7VCC")
		(16 "In7.Cu" signal "L8VCC")
		(18 "In8.Cu" signal "L9GND")
		(20 "In9.Cu" signal "L10")
		(22 "In10.Cu" signal "L11GND")
		(24 "In11.Cu" signal "L12")
		(26 "In12.Cu" signal "L13GND")
		(2 "B.Cu" signal "BOTTOM")
		(9 "F.Adhes" user "F.Adhesive")
		(11 "B.Adhes" user "B.Adhesive")
		(13 "F.Paste" user "Package Geometry/Pastemask Top")
		(15 "B.Paste" user "Package Geometry/Pastemask Bottom")
		(5 "F.SilkS" user "Ref Des/Silkscreen Top")
		(7 "B.SilkS" user "Ref Des/Silkscreen Bottom")
		(1 "F.Mask" user "Board Geometry/Soldermask Top")
		(3 "B.Mask" user "Board Geometry/Soldermask Bottom")
		(17 "Dwgs.User" user "User.Drawings")
		(19 "Cmts.User" user "User.Comments")
		(21 "Eco1.User" user "User.Eco1")
		(23 "Eco2.User" user "User.Eco2")
		(25 "Edge.Cuts" user "Board Geometry/Outline")
		(27 "Margin" user)
		(31 "F.CrtYd" user "Package Geometry/Place Bound Top")
		(29 "B.CrtYd" user "Package Geometry/Place Bound Bottom")
		(35 "F.Fab" user "Ref Des/Assembly Top")
		(33 "B.Fab" user "Ref Des/Assembly Bottom")
	)
	(footprint ""
		(layer "B.Cu")
		(at 368.709956 -121.443242 -90)
		(property "Reference" "C3M34"
			(at 0 0 90)
			(layer "B.SilkS")
			(hide yes)
			(effects
				(font
					(size 1.27 1.27)
				)
				(justify mirror)
			)
		)
		(property "Value" ""
			(at 0 0 90)
			(layer "B.Fab")
			(effects
				(font
					(size 1.27 1.27)
				)
				(justify mirror)
			)
		)
		(duplicate_pad_numbers_are_jumpers no)
		(fp_poly
			(pts
				(xy -0.3048 -0.1016) (xy -0.3048 0.9906) (xy 0.3048 0.9906) (xy 0.3048 -0.1016)
			)
			(stroke
				(width 0)
				(type default)
			)
			(fill no)
			(layer "B.CrtYd")
		)
		(fp_line
			(start -0.3048 0.9906)
			(end -0.3048 -0.1016)
			(stroke
				(width 0.1)
				(type default)
			)
			(layer "B.Fab")
		)
		(fp_line
			(start 0.3048 0.9906)
			(end -0.3048 0.9906)
			(stroke
				(width 0.1)
				(type default)
			)
			(layer "B.Fab")
		)
		(fp_line
			(start -0.3048 -0.1016)
			(end 0.3048 -0.1016)
			(stroke
				(width 0.1)
				(type default)
			)
			(layer "B.Fab")
		)
		(fp_line
			(start 0.3048 -0.1016)
			(end 0.3048 0.9906)
			(stroke
				(width 0.1)
				(type default)
			)
			(layer "B.Fab")
		)
		(pad "1" smd rect
			(at 0 0 90)
			(size 0.508 0.508)
			(layers "B.Cu" "B.Mask" "B.Paste")
			(net "P3E_CPU0_PE1_PCH_R_RXP<8>")
		)
		(pad "2" smd rect
			(at 0 0.889 90)
			(size 0.508 0.508)
			(layers "B.Cu" "B.Mask" "B.Paste")
			(net "P3E_CPU0_PE1_PCH_RXP<8>")
		)
		(zone
			(layer "B.Cu")
			(hatch none 0.5)
			(connect_pads
				(clearance 0)
			)
			(min_thickness 0.25)
			(keepout
				(tracks not_allowed)
				(vias allowed)
				(pads allowed)
				(copperpour not_allowed)
				(footprints allowed)
			)
			(placement
				(enabled no)
				(sheetname "")
			)
			(fill
				(thermal_gap 0.5)
				(thermal_bridge_width 0.5)
				(island_removal_mode 0)
			)
			(polygon
				(pts
					(xy 368.074956 -121.189242) (xy 368.074956 -121.697242) (xy 368.455956 -121.697242) (xy 368.455956 -121.189242)
				)
			)
		)
		(zone
			(layer "B.Cu")
			(hatch none 0.5)
			(connect_pads
				(clearance 0)
			)
			(min_thickness 0.25)
			(keepout
				(tracks allowed)
				(vias not_allowed)
				(pads allowed)
				(copperpour not_allowed)
				(footprints allowed)
			)
			(placement
				(enabled no)
				(sheetname "")
			)
			(fill
				(thermal_gap 0.5)
				(thermal_bridge_width 0.5)
				(island_removal_mode 0)
			)
			(polygon
				(pts
					(xy 368.455956 -121.189242) (xy 368.455956 -121.697242) (xy 368.074956 -121.697242) (xy 368.074956 -121.189242)
				)
			)
		)
	)
	(footprint ""
		(layer "B.Cu")
		(at 32.832802 -72.902064 90)
		(property "Reference" "C9P7"
			(at 0 0 90)
			(layer "B.SilkS")
			(hide yes)
			(effects
				(font
					(size 1.27 1.27)
				)
				(justify mirror)
			)
		)
		(property "Value" ""
			(at 0 0 90)
			(layer "B.Fab")
			(effects
				(font
					(size 1.27 1.27)
				)
				(justify mirror)
			)
		)
		(duplicate_pad_numbers_are_jumpers no)
		(fp_poly
			(pts
				(xy 0.7239 -0.2159) (xy -0.7239 -0.2159) (xy -0.7239 1.9939) (xy 0.7239 1.9939)
			)
			(stroke
				(width 0)
				(type default)
			)
			(fill no)
			(layer "B.CrtYd")
		)
		(fp_line
			(start 0.7239 -0.2159)
			(end 0.7239 1.9939)
			(stroke
				(width 0.1)
				(type default)
			)
			(layer "B.Fab")
		)
		(fp_line
			(start -0.7239 -0.2159)
			(end 0.7239 -0.2159)
			(stroke
				(width 0.1)
				(type default)
			)
			(layer "B.Fab")
		)
		(fp_line
			(start 0.7239 1.9939)
			(end -0.7239 1.9939)
			(stroke
				(width 0.1)
				(type default)
			)
			(layer "B.Fab")
		)
		(fp_line
			(start -0.7239 1.9939)
			(end -0.7239 -0.2159)
			(stroke
				(width 0.1)
				(type default)
			)
			(layer "B.Fab")
		)
		(pad "1" smd rect
			(at 0 0 270)
			(size 1.27 1.016)
			(layers "B.Cu" "B.Mask" "B.Paste")
			(net "VR_FET_SW_P12V_STBY_PVCCIN_CPU1")
		)
		(pad "2" smd rect
			(at 0 1.778 270)
			(size 1.27 1.016)
			(layers "B.Cu" "B.Mask" "B.Paste")
			(net "GND")
		)
		(zone
			(layer "B.Cu")
			(hatch none 0.5)
			(connect_pads
				(clearance 0)
			)
			(min_thickness 0.25)
			(keepout
				(tracks not_allowed)
				(vias allowed)
				(pads allowed)
				(copperpour not_allowed)
				(footprints allowed)
			)
			(placement
				(enabled no)
				(sheetname "")
			)
			(fill
				(thermal_gap 0.5)
				(thermal_bridge_width 0.5)
				(island_removal_mode 0)
			)
			(polygon
				(pts
					(xy 33.340802 -73.537064) (xy 33.340802 -72.267064) (xy 34.102802 -72.267064) (xy 34.102802 -73.537064)
				)
			)
		)
	)
	(footprint ""
		(layer "B.Cu")
		(at 369.5954 -5.3467 180)
		(property "Reference" "R7G28"
			(at 0 0 0)
			(layer "B.SilkS")
			(hide yes)
			(effects
				(font
					(size 1.27 1.27)
				)
				(justify mirror)
			)
		)
		(property "Value" ""
			(at 0 0 0)
			(layer "B.Fab")
			(effects
				(font
					(size 1.27 1.27)
				)
				(justify mirror)
			)
		)
		(duplicate_pad_numbers_are_jumpers no)
		(fp_poly
			(pts
				(xy 0.2794 -0.1016) (xy -0.2794 -0.1016) (xy -0.2794 0.9906) (xy 0.2794 0.9906)
			)
			(stroke
				(width 0)
				(type default)
			)
			(fill no)
			(layer "B.CrtYd")
		)
		(fp_line
			(start 0.2794 0.9906)
			(end -0.2794 0.9906)
			(stroke
				(width 0.1)
				(type default)
			)
			(layer "B.Fab")
		)
		(fp_line
			(start 0.2794 -0.1016)
			(end 0.2794 0.9906)
			(stroke
				(width 0.1)
				(type default)
			)
			(layer "B.Fab")
		)
		(fp_line
			(start -0.2794 0.9906)
			(end -0.2794 -0.1016)
			(stroke
				(width 0.1)
				(type default)
			)
			(layer "B.Fab")
		)
		(fp_line
			(start -0.2794 -0.1016)
			(end 0.2794 -0.1016)
			(stroke
				(width 0.1)
				(type default)
			)
			(layer "B.Fab")
		)
		(pad "1" smd rect
			(at 0 0)
			(size 0.508 0.508)
			(layers "B.Cu" "B.Mask" "B.Paste")
			(net "PD_ME_RCVR_N")
		)
		(pad "2" smd rect
			(at 0 0.889)
			(size 0.508 0.508)
			(layers "B.Cu" "B.Mask" "B.Paste")
			(net "GND")
		)
		(zone
			(layer "B.Cu")
			(hatch none 0.5)
			(connect_pads
				(clearance 0)
			)
			(min_thickness 0.25)
			(keepout
				(tracks not_allowed)
				(vias allowed)
				(pads allowed)
				(copperpour not_allowed)
				(footprints allowed)
			)
			(placement
				(enabled no)
				(sheetname "")
			)
			(fill
				(thermal_gap 0.5)
				(thermal_bridge_width 0.5)
				(island_removal_mode 0)
			)
			(polygon
				(pts
					(xy 369.3414 -5.9817) (xy 369.8494 -5.9817) (xy 369.8494 -5.6007) (xy 369.3414 -5.6007)
				)
			)
		)
		(zone
			(layer "B.Cu")
			(hatch none 0.5)
			(connect_pads
				(clearance 0)
			)
			(min_thickness 0.25)
			(keepout
				(tracks allowed)
				(vias not_allowed)
				(pads allowed)
				(copperpour not_allowed)
				(footprints allowed)
			)
			(placement
				(enabled no)
				(sheetname "")
			)
			(fill
				(thermal_gap 0.5)
				(thermal_bridge_width 0.5)
				(island_removal_mode 0)
			)
			(polygon
				(pts
					(xy 369.3414 -5.6007) (xy 369.8494 -5.6007) (xy 369.8494 -5.9817) (xy 369.3414 -5.9817)
				)
			)
		)
	)
	(footprint ""
		(layer "B.Cu")
		(at 393.03325 -110.0328 -90)
		(property "Reference" "C2N8"
			(at 0 0 90)
			(layer "B.SilkS")
			(hide yes)
			(effects
				(font
					(size 1.27 1.27)
				)
				(justify mirror)
			)
		)
		(property "Value" ""
			(at 0 0 90)
			(layer "B.Fab")
			(effects
				(font
					(size 1.27 1.27)
				)
				(justify mirror)
			)
		)
		(duplicate_pad_numbers_are_jumpers no)
		(fp_rect
			(start 0.2794 0.9144)
			(end -0.2794 -0.1143)
			(stroke
				(width 0)
				(type default)
			)
			(fill no)
			(layer "B.CrtYd")
		)
		(fp_line
			(start -0.2794 0.9144)
			(end 0.2794 0.9144)
			(stroke
				(width 0.1)
				(type default)
			)
			(layer "B.Fab")
		)
		(fp_line
			(start 0.2794 0.9144)
			(end 0.2794 -0.1143)
			(stroke
				(width 0.1)
				(type default)
			)
			(layer "B.Fab")
		)
		(fp_line
			(start -0.2794 -0.1143)
			(end -0.2794 0.9144)
			(stroke
				(width 0.1)
				(type default)
			)
			(layer "B.Fab")
		)
		(fp_line
			(start 0.2794 -0.1143)
			(end -0.2794 -0.1143)
			(stroke
				(width 0.1)
				(type default)
			)
			(layer "B.Fab")
		)
		(pad "1" smd custom
			(at 0 0 180)
			(size 0.10414 0.10414)
			(layers "B.Cu" "B.Mask" "B.Paste")
			(net "P1V05_PCH_STBY")
			(options
				(clearance outline)
				(anchor circle)
			)
			(primitives
				(gr_poly
					(pts
						(xy -0.20828 -0.08636) (xy -0.20828 0.08636) (xy -0.08636 0.20828) (xy 0.086614 0.20828) (xy 0.20828 0.086614)
						(xy 0.20828 -0.08636) (xy 0.08636 -0.20828) (xy -0.08636 -0.20828)
					)
					(width 0)
					(fill yes)
				)
			)
		)
		(pad "2" smd custom
			(at 0 0.8001 180)
			(size 0.10414 0.10414)
			(layers "B.Cu" "B.Mask" "B.Paste")
			(net "GND")
			(options
				(clearance outline)
				(anchor circle)
			)
			(primitives
				(gr_poly
					(pts
						(xy -0.20828 -0.08636) (xy -0.20828 0.08636) (xy -0.08636 0.20828) (xy 0.086614 0.20828) (xy 0.20828 0.086614)
						(xy 0.20828 -0.08636) (xy 0.08636 -0.20828) (xy -0.08636 -0.20828)
					)
					(width 0)
					(fill yes)
				)
			)
		)
		(zone
			(layer "B.Cu")
			(hatch none 0.5)
			(connect_pads
				(clearance 0)
			)
			(min_thickness 0.25)
			(keepout
				(tracks not_allowed)
				(vias allowed)
				(pads allowed)
				(copperpour not_allowed)
				(footprints allowed)
			)
			(placement
				(enabled no)
				(sheetname "")
			)
			(fill
				(thermal_gap 0.5)
				(thermal_bridge_width 0.5)
				(island_removal_mode 0)
			)
			(polygon
				(pts
					(xy 392.8237 -109.94517) (xy 392.4427 -109.94517) (xy 392.4427 -110.12043) (xy 392.8237 -110.120684)
				)
			)
		)
		(zone
			(layer "B.Cu")
			(hatch none 0.5)
			(connect_pads
				(clearance 0)
			)
			(min_thickness 0.25)
			(keepout
				(tracks allowed)
				(vias not_allowed)
				(pads allowed)
				(copperpour not_allowed)
				(footprints allowed)
			)
			(placement
				(enabled no)
				(sheetname "")
			)
			(fill
				(thermal_gap 0.5)
				(thermal_bridge_width 0.5)
				(island_removal_mode 0)
			)
			(polygon
				(pts
					(xy 392.8237 -109.94517) (xy 392.4427 -109.94517) (xy 392.4427 -110.12043) (xy 392.8237 -110.120684)
				)
			)
		)
	)
	(footprint ""
		(layer "B.Cu")
		(at 373.9642 -155.432506)
		(property "Reference" "R3L1"
			(at 0 0 0)
			(layer "B.SilkS")
			(hide yes)
			(effects
				(font
					(size 1.27 1.27)
				)
				(justify mirror)
			)
		)
		(property "Value" ""
			(at 0 0 0)
			(layer "B.Fab")
			(effects
				(font
					(size 1.27 1.27)
				)
				(justify mirror)
			)
		)
		(duplicate_pad_numbers_are_jumpers no)
		(fp_poly
			(pts
				(xy 0.2794 -0.1016) (xy -0.2794 -0.1016) (xy -0.2794 0.9906) (xy 0.2794 0.9906)
			)
			(stroke
				(width 0)
				(type default)
			)
			(fill no)
			(layer "B.CrtYd")
		)
		(fp_line
			(start -0.2794 -0.1016)
			(end 0.2794 -0.1016)
			(stroke
				(width 0.1)
				(type default)
			)
			(layer "B.Fab")
		)
		(fp_line
			(start -0.2794 0.9906)
			(end -0.2794 -0.1016)
			(stroke
				(width 0.1)
				(type default)
			)
			(layer "B.Fab")
		)
		(fp_line
			(start 0.2794 -0.1016)
			(end 0.2794 0.9906)
			(stroke
				(width 0.1)
				(type default)
			)
			(layer "B.Fab")
		)
		(fp_line
			(start 0.2794 0.9906)
			(end -0.2794 0.9906)
			(stroke
				(width 0.1)
				(type default)
			)
			(layer "B.Fab")
		)
		(pad "1" smd rect
			(at 0 0 180)
			(size 0.508 0.508)
			(layers "B.Cu" "B.Mask" "B.Paste")
			(net "VR_PVNN_PCH_PH1_VCIN")
		)
		(pad "2" smd rect
			(at 0 0.889 180)
			(size 0.508 0.508)
			(layers "B.Cu" "B.Mask" "B.Paste")
			(net "P5V_STBY")
		)
		(zone
			(layer "B.Cu")
			(hatch none 0.5)
			(connect_pads
				(clearance 0)
			)
			(min_thickness 0.25)
			(keepout
				(tracks allowed)
				(vias not_allowed)
				(pads allowed)
				(copperpour not_allowed)
				(footprints allowed)
			)
			(placement
				(enabled no)
				(sheetname "")
			)
			(fill
				(thermal_gap 0.5)
				(thermal_bridge_width 0.5)
				(island_removal_mode 0)
			)
			(polygon
				(pts
					(xy 374.2182 -155.178506) (xy 373.7102 -155.178506) (xy 373.7102 -154.797506) (xy 374.2182 -154.797506)
				)
			)
		)
		(zone
			(layer "B.Cu")
			(hatch none 0.5)
			(connect_pads
				(clearance 0)
			)
			(min_thickness 0.25)
			(keepout
				(tracks not_allowed)
				(vias allowed)
				(pads allowed)
				(copperpour not_allowed)
				(footprints allowed)
			)
			(placement
				(enabled no)
				(sheetname "")
			)
			(fill
				(thermal_gap 0.5)
				(thermal_bridge_width 0.5)
				(island_removal_mode 0)
			)
			(polygon
				(pts
					(xy 374.2182 -154.797506) (xy 373.7102 -154.797506) (xy 373.7102 -155.178506) (xy 374.2182 -155.178506)
				)
			)
		)
	)
	(footprint ""
		(layer "B.Cu")
		(at 60.28182 -103.87584)
		(property "Reference" ""
			(at 0 0 0)
			(layer "B.SilkS")
			(hide yes)
			(effects
				(font
					(size 1.27 1.27)
				)
				(justify mirror)
			)
		)
		(property "Value" ""
			(at 0 0 0)
			(layer "B.Fab")
			(effects
				(font
					(size 1.27 1.27)
				)
				(justify mirror)
			)
		)
		(duplicate_pad_numbers_are_jumpers no)
		(fp_poly
			(pts
				(arc
					(start 2.032 0)
					(mid -2.032 0)
					(end 2.032 0)
				)
			)
			(stroke
				(width 0)
				(type default)
			)
			(fill no)
			(layer "B.CrtYd")
		)
		(pad "1" smd circle
			(at 0 0 180)
			(size 1.016 1.016)
			(layers "B.Cu" "B.Mask" "B.Paste")
			(net "Net_387")
		)
		(zone
			(layers "F.Cu" "B.Cu" "In1.Cu" "In2.Cu" "In3.Cu" "In4.Cu" "In5.Cu" "In6.Cu"
				"In7.Cu" "In8.Cu" "In9.Cu" "In10.Cu" "In11.Cu" "In12.Cu"
			)
			(hatch none 0.5)
			(connect_pads
				(clearance 0)
			)
			(min_thickness 0.25)
			(keepout
				(tracks allowed)
				(vias not_allowed)
				(pads allowed)
				(copperpour not_allowed)
				(footprints allowed)
			)
			(placement
				(enabled no)
				(sheetname "")
			)
			(fill
				(thermal_gap 0.5)
				(thermal_bridge_width 0.5)
				(island_removal_mode 0)
			)
			(polygon
				(pts
					(arc
						(start 61.80582 -103.87584)
						(mid 58.75782 -103.87584)
						(end 61.80582 -103.87584)
					)
				)
			)
		)
		(zone
			(layer "B.Cu")
			(hatch none 0.5)
			(connect_pads
				(clearance 0)
			)
			(min_thickness 0.25)
			(keepout
				(tracks not_allowed)
				(vias allowed)
				(pads allowed)
				(copperpour not_allowed)
				(footprints allowed)
			)
			(placement
				(enabled no)
				(sheetname "")
			)
			(fill
				(thermal_gap 0.5)
				(thermal_bridge_width 0.5)
				(island_removal_mode 0)
			)
			(polygon
				(pts
					(arc
						(start 61.80582 -103.87584)
						(mid 58.75782 -103.87584)
						(end 61.80582 -103.87584)
					)
				)
			)
		)
	)
	(footprint ""
		(layer "B.Cu")
		(at 128.8796 -66.292984 180)
		(property "Reference" "R7P27"
			(at 0 0 0)
			(layer "B.SilkS")
			(hide yes)
			(effects
				(font
					(size 1.27 1.27)
				)
				(justify mirror)
			)
		)
		(property "Value" ""
			(at 0 0 0)
			(layer "B.Fab")
			(effects
				(font
					(size 1.27 1.27)
				)
				(justify mirror)
			)
		)
		(duplicate_pad_numbers_are_jumpers no)
		(fp_poly
			(pts
				(xy 0.2794 -0.1016) (xy -0.2794 -0.1016) (xy -0.2794 0.9906) (xy 0.2794 0.9906)
			)
			(stroke
				(width 0)
				(type default)
			)
			(fill no)
			(layer "B.CrtYd")
		)
		(fp_line
			(start 0.2794 0.9906)
			(end -0.2794 0.9906)
			(stroke
				(width 0.1)
				(type default)
			)
			(layer "B.Fab")
		)
		(fp_line
			(start 0.2794 -0.1016)
			(end 0.2794 0.9906)
			(stroke
				(width 0.1)
				(type default)
			)
			(layer "B.Fab")
		)
		(fp_line
			(start -0.2794 0.9906)
			(end -0.2794 -0.1016)
			(stroke
				(width 0.1)
				(type default)
			)
			(layer "B.Fab")
		)
		(fp_line
			(start -0.2794 -0.1016)
			(end 0.2794 -0.1016)
			(stroke
				(width 0.1)
				(type default)
			)
			(layer "B.Fab")
		)
		(pad "1" smd rect
			(at 0 0)
			(size 0.508 0.508)
			(layers "B.Cu" "B.Mask" "B.Paste")
			(net "PVCCIO_CPU0")
		)
		(pad "2" smd rect
			(at 0 0.889)
			(size 0.508 0.508)
			(layers "B.Cu" "B.Mask" "B.Paste")
			(net "H_CPU1_MSMI_G_N")
		)
		(zone
			(layer "B.Cu")
			(hatch none 0.5)
			(connect_pads
				(clearance 0)
			)
			(min_thickness 0.25)
			(keepout
				(tracks not_allowed)
				(vias allowed)
				(pads allowed)
				(copperpour not_allowed)
				(footprints allowed)
			)
			(placement
				(enabled no)
				(sheetname "")
			)
			(fill
				(thermal_gap 0.5)
				(thermal_bridge_width 0.5)
				(island_removal_mode 0)
			)
			(polygon
				(pts
					(xy 128.6256 -66.927984) (xy 129.1336 -66.927984) (xy 129.1336 -66.546984) (xy 128.6256 -66.546984)
				)
			)
		)
		(zone
			(layer "B.Cu")
			(hatch none 0.5)
			(connect_pads
				(clearance 0)
			)
			(min_thickness 0.25)
			(keepout
				(tracks allowed)
				(vias not_allowed)
				(pads allowed)
				(copperpour not_allowed)
				(footprints allowed)
			)
			(placement
				(enabled no)
				(sheetname "")
			)
			(fill
				(thermal_gap 0.5)
				(thermal_bridge_width 0.5)
				(island_removal_mode 0)
			)
			(polygon
				(pts
					(xy 128.6256 -66.546984) (xy 129.1336 -66.546984) (xy 129.1336 -66.927984) (xy 128.6256 -66.927984)
				)
			)
		)
	)
)
